FILE_TYPE = CONNECTIVITY;
{Allegro Design Entry HDL 17.4-2019 S026 (4007227) 1/17/2022}
"PAGE_NUMBER" = 295;
0"NC";
1"GND\g";
2"GND\g";
3"P3V3_AUX\g";
4"P3V3_AUX\g";
5"GND\g";
6"GND\g";
7"OCP_SFF_P3V3_ADC_ALERT_R";
8"E1S_0_P3V3_ADC_ALERT_R";
9"E1S_0_P3V3_P12V_ADC_R_ALERT";
10"P3V3_OCP_SFF_R\g";
11"INA230_1_A1";
12"VSENSE_P3V3_INA230_1_INP";
13"VSENSE_P3V3_INA230_1_INN";
14"NC_INA230_2_NC5";
15"OCP_SFF_P3V3_P12V_ADC_R_ALERT";
16"NC_INA230_1_NC1";
17"NC_INA230_1_NC3";
18"NC_INA230_1_NC5";
19"P3V3_OCP_SFF_R\g";
20"P3V3_OCP_SFF\g";
21"P3V3_E1S_0_R\g";
22"NC_INA230_1_NC4";
23"INA230_1_A0";
24"GND\g";
25"NC_INA230_1_NC2";
26"NC_INA230_1_NC0";
27"P3V3_AUX\g";
28"INA230_2_A0";
29"NC_INA230_2_NC0";
30"NC_INA230_2_NC2";
31"GND\g";
32"VSENSE_P3V3_INA230_2_INN";
33"VSENSE_P3V3_INA230_2_INP";
34"NC_INA230_2_NC4";
35"GND\g";
36"P3V3_E1S_0\g";
37"P3V3_E1S_0_R\g";
38"GND\g";
39"P3V3_AUX\g";
40"SMB_INA230_1_3V3AUX_SCL_R1";
41"SMB_INA230_2_3V3AUX_SCL_R";
42"SMB_INA230_2_3V3AUX_SDA_R1";
43"SMB_INA230_2_3V3AUX_SCL_R1";
44"SMB_INA230_1_3V3AUX_SDA_R";
45"SMB_INA230_1_3V3AUX_SCL_R";
46"NC_INA230_2_NC3";
47"NC_INA230_2_NC1";
48"SMB_INA230_2_3V3AUX_SDA_R";
49"INA230_2_A1";
50"P3V3_AUX\g";
51"SMB_INA230_1_3V3AUX_SDA_R1";
%"Q_RES"
"1","(4450,725)","0","pure_quanta","I122";
;
LOCATION"R3752"
$SEC"1"
CDS_SEC"1"
VALUE"0"
MATERIAL"CHIP"
PACK_TYPE"0402LF"
CDS_LIB"pure_quanta"
TOLERANCE"5%"
WATTAGE"1/16W"
PART_NUMBER"CS00002JB13";
"B"
$PN"2"9;
"A"
$PN"1"8;
%"UNIVERSAL_POWER"
"1","(2425,1475)","0","pure_quanta_power","I123";
;
HDL_POWER"P3V3_AUX"
CDS_LIB"pure_quanta_power";
"A"50;
%"UNIVERSAL_GND"
"1","(2175,800)","0","pure_quanta_power","I124";
;
CDS_LIB"pure_quanta_power"
HDL_POWER"GND";
"A"1;
%"Q_CAP"
"1","(2175,1075)","0","pure_quanta","I125";
;
LOCATION"C2067"
$SEC"1"
CDS_SEC"1"
VOLTAGE"25V"
VALUE"0.1UF"
TOLERANCE"10%"
MATERIAL"X7R"
PACK_TYPE"0402"
CDS_LIB"pure_quanta"
PART_NUMBER"CH4104K1B00";
"B"
$PN"2"1;
"A"
$PN"1"50;
%"UNIVERSAL_GND"
"1","(3500,-175)","0","pure_quanta_power","I128";
;
CDS_LIB"pure_quanta_power"
HDL_POWER"GND";
"A"31;
%"ISL28022FRZT"
"1","(2925,475)","0","pure_quanta","I129";
;
LOCATION"U276"
SEC"1"
MATERIAL"IC"
VALUE"ISL28022FRZ-T"
PART_TYPE"SMLF"
CDS_LIB"pure_quanta"
NEEDS_NO_SIZE"TRUE"
CDS_LMAN_SYM_OUTLINE"-300,300,300,-300"
SEC_TYPE""
PART_NUMBER"AL028022003";
"TH_GND"
$PN"TH"31;
"GND"
$PN"10"31;
"NC5"
$PN"16"14;
"NC4"
$PN"15"34;
"NC3"
$PN"14"46;
"NC2"
$PN"8"30;
"NC1"
$PN"7"47;
"NC0"
$PN"6"29;
"EXT_CLK||INT"
$PN"3"8;
"VINM"
$PN"12"32;
"VINP"
$PN"13"33;
"VBUS"
$PN"11"37;
"SDA||SMBDAT"
$PN"4"42;
"SCL|||SMBCLK"
$PN"5"43;
"A0"
$PN"2"28;
"A1"
$PN"1"49;
"VCC"
$PN"9"50;
%"Q_RES"
"1","(1300,-125)","0","pure_quanta","I132";
;
LOCATION"R3758"
$SEC"1"
CDS_SEC"1"
MATERIAL"CHIP"
VALUE"10"
TOLERANCE"1%"
PACK_TYPE"0402LF"
WATTAGE"1/16W"
CDS_LIB"pure_quanta"
PART_NUMBER"CS01002FB07";
"B"
$PN"2"33;
"A"
$PN"1"21;
%"Q_CAP"
"1","(1650,-275)","0","pure_quanta","I133";
;
LOCATION"C2071"
$SEC"1"
CDS_SEC"1"
PACK_TYPE"0402"
VALUE"0.1UF"
TOLERANCE"10%"
VOLTAGE"25V"
MATERIAL"X7R"
CDS_LIB"pure_quanta"
PART_NUMBER"CH4104K1B00";
"B"
$PN"2"32;
"A"
$PN"1"33;
%"Q_RES"
"1","(1300,-400)","0","pure_quanta","I134";
;
LOCATION"R3760"
$SEC"1"
CDS_SEC"1"
MATERIAL"CHIP"
PACK_TYPE"0402LF"
TOLERANCE"1%"
VALUE"10"
WATTAGE"1/16W"
CDS_LIB"pure_quanta"
PART_NUMBER"CS01002FB07";
"B"
$PN"2"32;
"A"
$PN"1"36;
%"Q_RES"
"1","(750,1000)","0","pure_quanta","I135";
;
LOCATION"R3764"
$SEC"1"
CDS_SEC"1"
VALUE"4.7K"
WATTAGE"1/16W"
MATERIAL"EMPTY"
PACK_TYPE"0402LF"
TOLERANCE"1%"
CDS_LIB"pure_quanta"
PART_NUMBER"CS24702FB06";
"B"
$PN"2"28;
"A"
$PN"1"35;
%"Q_RES"
"1","(750,1075)","0","pure_quanta","I136";
;
LOCATION"R3763"
$SEC"1"
CDS_SEC"1"
MATERIAL"CHIP"
TOLERANCE"1%"
WATTAGE"1/16W"
VALUE"4.7K"
PACK_TYPE"0402LF"
CDS_LIB"pure_quanta"
PART_NUMBER"CS24702FB06";
"B"
$PN"2"49;
"A"
$PN"1"35;
%"UNIVERSAL_GND"
"1","(175,875)","0","pure_quanta_power","I137";
;
CDS_LIB"pure_quanta_power"
HDL_POWER"GND";
"A"35;
%"UNIVERSAL_POWER"
"1","(-100,225)","0","pure_quanta_power","I140";
;
HDL_POWER"P3V3_E1S_0_R"
CDS_LIB"pure_quanta_power";
"A"21;
%"Q_CAP"
"1","(-500,650)","0","pure_quanta","I142";
;
LOCATION"C2069"
$SEC"1"
CDS_SEC"1"
VALUE"0.1UF"
PACK_TYPE"0402"
TOLERANCE"10%"
VOLTAGE"25V"
MATERIAL"X7R"
CDS_LIB"pure_quanta"
PART_NUMBER"CH4104K1B00";
"B"
$PN"2"2;
"A"
$PN"1"37;
%"UNIVERSAL_GND"
"1","(-500,375)","0","pure_quanta_power","I143";
;
CDS_LIB"pure_quanta_power"
HDL_POWER"GND";
"A"2;
%"Q_RES"
"1","(-600,75)","0","pure_quanta","I144";
;
LOCATION"R3767"
$SEC"1"
CDS_SEC"1"
PACK_TYPE"2512LF"
MATERIAL"CHIP"
TOLERANCE"1%"
VALUE"0.002"
WATTAGE"2W"
CDS_LIB"pure_quanta"
PART_NUMBER"CS+002AFR06";
"B"
$PN"2"21;
"A"
$PN"1"36;
%"UNIVERSAL_POWER"
"1","(-1175,225)","0","pure_quanta_power","I145";
;
HDL_POWER"P3V3_E1S_0"
CDS_LIB"pure_quanta_power";
"A"36;
%"Q_RES"
"2","(1550,825)","0","pure_quanta","I146";
;
LOCATION"R3751"
$SEC"1"
CDS_SEC"1"
WATTAGE"1/16W"
MATERIAL"CHIP"
TOLERANCE"5%"
VALUE"0"
PACK_TYPE"0402LF"
CDS_LIB"pure_quanta"
PART_NUMBER"CS00002JB13";
"A"
$PN"1"28;
"B"
$PN"2"42;
%"UNIVERSAL_POWER"
"1","(-250,975)","0","pure_quanta_power","I147";
;
HDL_POWER"P3V3_E1S_0_R"
CDS_LIB"pure_quanta_power";
"A"37;
%"UNIVERSAL_POWER"
"1","(4225,1375)","0","pure_quanta_power","I148";
;
HDL_POWER"P3V3_AUX"
CDS_LIB"pure_quanta_power";
"A"3;
%"Q_RES"
"2","(4225,1175)","0","pure_quanta","I149";
;
LOCATION"R4093"
$SEC"1"
CDS_SEC"1"
TOLERANCE"1%"
VALUE"1K"
WATTAGE"1/16W"
MATERIAL"CHIP"
PACK_TYPE"0402LF"
CDS_LIB"pure_quanta"
PART_NUMBER"CS21002FB06";
"A"
$PN"1"3;
"B"
$PN"2"8;
%"UNIVERSAL_POWER"
"1","(4250,3975)","0","pure_quanta_power","I150";
;
HDL_POWER"P3V3_AUX"
CDS_LIB"pure_quanta_power";
"A"4;
%"Q_RES"
"2","(4250,3775)","0","pure_quanta","I151";
;
LOCATION"R4094"
$SEC"1"
CDS_SEC"1"
TOLERANCE"1%"
WATTAGE"1/16W"
MATERIAL"CHIP"
VALUE"1K"
PACK_TYPE"0402LF"
CDS_LIB"pure_quanta"
PART_NUMBER"CS21002FB06";
"A"
$PN"1"4;
"B"
$PN"2"7;
%"Q_RES"
"1","(1275,3075)","0","pure_quanta","I152";
;
LOCATION"R3600"
$SEC"1"
CDS_SEC"1"
PACK_TYPE"0402LF"
WATTAGE"1/16W"
VALUE"0"
TOLERANCE"5%"
MATERIAL"CHIP"
CDS_LIB"pure_quanta"
PART_NUMBER"CS00002JB13";
"B"
$PN"2"40;
"A"
$PN"1"45;
%"Q_RES"
"1","(1275,3025)","0","pure_quanta","I153";
;
LOCATION"R3601"
$SEC"1"
CDS_SEC"1"
MATERIAL"CHIP"
TOLERANCE"5%"
VALUE"0"
WATTAGE"1/16W"
PACK_TYPE"0402LF"
CDS_LIB"pure_quanta"
PART_NUMBER"CS00002JB13";
"B"
$PN"2"51;
"A"
$PN"1"44;
%"Q_RES"
"1","(1275,425)","0","pure_quanta","I154";
;
LOCATION"R3756"
$SEC"1"
CDS_SEC"1"
VALUE"0"
TOLERANCE"5%"
MATERIAL"CHIP"
PACK_TYPE"0402LF"
WATTAGE"1/16W"
CDS_LIB"pure_quanta"
PART_NUMBER"CS00002JB13";
"B"
$PN"2"42;
"A"
$PN"1"48;
%"Q_RES"
"1","(1275,475)","0","pure_quanta","I155";
;
LOCATION"R3754"
$SEC"1"
CDS_SEC"1"
WATTAGE"1/16W"
PACK_TYPE"0402LF"
MATERIAL"CHIP"
TOLERANCE"5%"
VALUE"0"
CDS_LIB"pure_quanta"
PART_NUMBER"CS00002JB13";
"B"
$PN"2"43;
"A"
$PN"1"41;
%"ISL28022FRZT"
"1","(2925,3075)","0","pure_quanta","I30";
;
LOCATION"U266"
SEC"1"
PART_TYPE"SMLF"
MATERIAL"IC"
VALUE"ISL28022FRZ-T"
SEC_TYPE""
CDS_LMAN_SYM_OUTLINE"-300,300,300,-300"
NEEDS_NO_SIZE"TRUE"
CDS_LIB"pure_quanta"
PART_NUMBER"AL028022003";
"TH_GND"
$PN"TH"24;
"GND"
$PN"10"24;
"NC5"
$PN"16"18;
"NC4"
$PN"15"22;
"NC3"
$PN"14"17;
"NC2"
$PN"8"25;
"NC1"
$PN"7"16;
"NC0"
$PN"6"26;
"EXT_CLK||INT"
$PN"3"7;
"VINM"
$PN"12"13;
"VINP"
$PN"13"12;
"VBUS"
$PN"11"10;
"SDA||SMBDAT"
$PN"4"51;
"SCL|||SMBCLK"
$PN"5"40;
"A0"
$PN"2"23;
"A1"
$PN"1"11;
"VCC"
$PN"9"27;
%"Q_RES"
"1","(625,3350)","0","pure_quanta","I31";
;
LOCATION"R3616"
$SEC"1"
CDS_SEC"1"
PACK_TYPE"0402LF"
MATERIAL"CHIP"
VALUE"4.7K"
TOLERANCE"1%"
WATTAGE"1/16W"
CDS_LIB"pure_quanta"
PART_NUMBER"CS24702FB06";
"B"
$PN"2"11;
"A"
$PN"1"38;
%"UNIVERSAL_POWER"
"1","(2425,4075)","0","pure_quanta_power","I33";
;
HDL_POWER"P3V3_AUX"
CDS_LIB"pure_quanta_power";
"A"27;
%"Q_CAP"
"1","(2175,3675)","0","pure_quanta","I34";
;
LOCATION"C2015"
$SEC"1"
CDS_SEC"1"
VALUE"0.1UF"
VOLTAGE"25V"
MATERIAL"X7R"
TOLERANCE"10%"
PACK_TYPE"0402"
CDS_LIB"pure_quanta"
PART_NUMBER"CH4104K1B00";
"B"
$PN"2"5;
"A"
$PN"1"27;
%"Q_RES"
"1","(4450,3325)","0","pure_quanta","I35";
;
LOCATION"R3563"
$SEC"1"
CDS_SEC"1"
MATERIAL"CHIP"
VALUE"0"
PACK_TYPE"0402LF"
WATTAGE"1/16W"
TOLERANCE"5%"
CDS_LIB"pure_quanta"
PART_NUMBER"CS00002JB13";
"B"
$PN"2"15;
"A"
$PN"1"7;
%"UNIVERSAL_GND"
"1","(3500,2425)","0","pure_quanta_power","I36";
;
CDS_LIB"pure_quanta_power"
HDL_POWER"GND";
"A"24;
%"UNIVERSAL_GND"
"1","(2175,3400)","0","pure_quanta_power","I37";
;
CDS_LIB"pure_quanta_power"
HDL_POWER"GND";
"A"5;
%"Q_RES"
"1","(625,3275)","0","pure_quanta","I40";
;
LOCATION"R3617"
$SEC"1"
CDS_SEC"1"
TOLERANCE"1%"
WATTAGE"1/16W"
VALUE"4.7K"
PACK_TYPE"0402LF"
MATERIAL"EMPTY"
CDS_LIB"pure_quanta"
PART_NUMBER"CS24702FB06";
"B"
$PN"2"23;
"A"
$PN"1"38;
%"Q_RES"
"1","(1300,2475)","0","pure_quanta","I41";
;
LOCATION"R3602"
$SEC"1"
CDS_SEC"1"
WATTAGE"1/16W"
VALUE"10"
PACK_TYPE"0402LF"
MATERIAL"CHIP"
TOLERANCE"1%"
CDS_LIB"pure_quanta"
PART_NUMBER"CS01002FB07";
"B"
$PN"2"12;
"A"
$PN"1"19;
%"Q_RES"
"1","(1300,2200)","0","pure_quanta","I43";
;
LOCATION"R3603"
$SEC"1"
CDS_SEC"1"
TOLERANCE"1%"
PACK_TYPE"0402LF"
VALUE"10"
WATTAGE"1/16W"
MATERIAL"CHIP"
CDS_LIB"pure_quanta"
PART_NUMBER"CS01002FB07";
"B"
$PN"2"13;
"A"
$PN"1"20;
%"UNIVERSAL_GND"
"1","(200,3150)","0","pure_quanta_power","I45";
;
CDS_LIB"pure_quanta_power"
HDL_POWER"GND";
"A"38;
%"UNIVERSAL_GND"
"1","(-500,2975)","0","pure_quanta_power","I49";
;
CDS_LIB"pure_quanta_power"
HDL_POWER"GND";
"A"6;
%"Q_CAP"
"1","(-500,3250)","0","pure_quanta","I50";
;
LOCATION"C2024"
$SEC"1"
CDS_SEC"1"
VALUE"0.1UF"
VOLTAGE"25V"
TOLERANCE"10%"
PACK_TYPE"0402"
MATERIAL"X7R"
CDS_LIB"pure_quanta"
PART_NUMBER"CH4104K1B00";
"B"
$PN"2"6;
"A"
$PN"1"10;
%"Q_CAP"
"1","(1650,2325)","0","pure_quanta","I77";
;
LOCATION"C2027"
$SEC"1"
CDS_SEC"1"
VALUE"0.1UF"
VOLTAGE"25V"
TOLERANCE"10%"
MATERIAL"X7R"
PACK_TYPE"0402"
CDS_LIB"pure_quanta"
PART_NUMBER"CH4104K1B00";
"B"
$PN"2"13;
"A"
$PN"1"12;
%"UNIVERSAL_POWER"
"1","(-100,2825)","0","pure_quanta_power","I79";
;
HDL_POWER"P3V3_OCP_SFF_R"
CDS_LIB"pure_quanta_power";
"A"19;
%"UNIVERSAL_POWER"
"1","(-250,3575)","0","pure_quanta_power","I80";
;
HDL_POWER"P3V3_OCP_SFF_R"
CDS_LIB"pure_quanta_power";
"A"10;
%"UNIVERSAL_POWER"
"1","(-1175,2825)","0","pure_quanta_power","I81";
;
HDL_POWER"P3V3_OCP_SFF"
CDS_LIB"pure_quanta_power";
"A"20;
%"UNIVERSAL_POWER"
"1","(1825,4125)","0","pure_quanta_power","I87";
;
HDL_POWER"P3V3_AUX"
CDS_LIB"pure_quanta_power";
"A"39;
%"Q_RES"
"2","(1825,3700)","0","pure_quanta","I88";
;
LOCATION"R3628"
$SEC"1"
CDS_SEC"1"
VALUE"4.7K"
WATTAGE"1/16W"
TOLERANCE"1%"
MATERIAL"EMPTY"
PACK_TYPE"0402LF"
CDS_LIB"pure_quanta"
PART_NUMBER"CS24702FB06";
"A"
$PN"1"39;
"B"
$PN"2"11;
%"Q_RES"
"2","(1525,3700)","0","pure_quanta","I89";
;
LOCATION"R3627"
$SEC"1"
CDS_SEC"1"
TOLERANCE"1%"
PACK_TYPE"0402LF"
VALUE"4.7K"
MATERIAL"CHIP"
WATTAGE"1/16W"
CDS_LIB"pure_quanta"
PART_NUMBER"CS24702FB06";
"A"
$PN"1"39;
"B"
$PN"2"23;
%"Q_RES"
"1","(-600,2675)","0","pure_quanta","I93";
;
LOCATION"R3645"
$SEC"1"
CDS_SEC"1"
WATTAGE"2W"
VALUE"0.002"
TOLERANCE"1%"
MATERIAL"CHIP"
PACK_TYPE"2512LF"
CDS_LIB"pure_quanta"
PART_NUMBER"CS+002AFR06";
"B"
$PN"2"19;
"A"
$PN"1"20;
END.
